(kicad_pcb
	(version 20260206)
	(generator "pcbnew")
	(generator_version "10.0")
	(general
		(thickness 1.6)
		(legacy_teardrops no)
	)
	(paper "A4")
	(title_block
		(title "Bryce Canyon_F.DPB_16315-1-OCP.brd")
		(comment 1 "Bryce Canyon / footprints 1910-1916 of 2223")
	)
	(layers
		(0 "F.Cu" signal "TOP")
		(4 "In1.Cu" signal "L2GND")
		(6 "In2.Cu" signal "L3")
		(8 "In3.Cu" signal "L4GND")
		(10 "In4.Cu" signal "L5")
		(12 "In5.Cu" signal "L6VCC")
		(14 "In6.Cu" signal "L7VCC")
		(16 "In7.Cu" signal "L8")
		(18 "In8.Cu" signal "L9GND")
		(20 "In9.Cu" signal "L10")
		(22 "In10.Cu" signal "L11GND")
		(2 "B.Cu" signal "BOTTOM")
		(9 "F.Adhes" user "F.Adhesive")
		(11 "B.Adhes" user "B.Adhesive")
		(13 "F.Paste" user "Package Geometry/Pastemask Top")
		(15 "B.Paste" user "Package Geometry/Pastemask Bottom")
		(5 "F.SilkS" user "Ref Des/Silkscreen Top")
		(7 "B.SilkS" user "Ref Des/Silkscreen Bottom")
		(1 "F.Mask" user "Board Geometry/Soldermask Top")
		(3 "B.Mask" user "Board Geometry/Soldermask Bottom")
		(17 "Dwgs.User" user "User.Drawings")
		(19 "Cmts.User" user "User.Comments")
		(21 "Eco1.User" user "User.Eco1")
		(23 "Eco2.User" user "User.Eco2")
		(25 "Edge.Cuts" user "Board Geometry/Outline")
		(27 "Margin" user)
		(31 "F.CrtYd" user "Package Geometry/Place Bound Top")
		(29 "B.CrtYd" user "Package Geometry/Place Bound Bottom")
		(35 "F.Fab" user "Ref Des/Assembly Top")
		(33 "B.Fab" user "Ref Des/Assembly Bottom")
	)
	(footprint ""
		(layer "F.Cu")
		(at 363.655102 -157.585918)
		(property "Reference" "R579"
			(at 0 0 0)
			(layer "F.SilkS")
			(hide yes)
			(effects
				(font
					(size 1.27 1.27)
				)
			)
		)
		(property "Value" "4K7R2J-2-GP"
			(at 0.064008 -3.993896 0)
			(unlocked yes)
			(layer "F.Fab")
			(hide yes)
			(effects
				(font
					(size 1.016 1.016)
					(thickness 0.1524)
				)
			)
		)
		(property "Device Type" "R402H16"
			(at 0.064008 -5.517896 0)
			(unlocked yes)
			(layer "F.Fab")
			(hide yes)
			(effects
				(font
					(size 1.016 1.016)
					(thickness 0.1524)
				)
			)
		)
		(duplicate_pad_numbers_are_jumpers no)
		(fp_line
			(start -0.508 -0.9398)
			(end -0.508 0.9398)
			(stroke
				(width 0.1524)
				(type default)
			)
			(layer "F.SilkS")
		)
		(fp_line
			(start 0.508 -0.9398)
			(end -0.508 -0.9398)
			(stroke
				(width 0.1524)
				(type default)
			)
			(layer "F.SilkS")
		)
		(fp_rect
			(start -0.508 0.9398)
			(end 0.508 -0.9398)
			(stroke
				(width 0)
				(type default)
			)
			(fill no)
			(layer "F.CrtYd")
		)
		(fp_rect
			(start -0.508 0.9398)
			(end 0.508 -0.9398)
			(stroke
				(width 0)
				(type default)
			)
			(fill no)
			(layer "F.Fab")
		)
		(pad "1" smd custom
			(at 0 -0.4445)
			(size 0.1397 0.1397)
			(layers "F.Cu" "F.Mask" "F.Paste")
			(net "SW_PWR_R_HDD19")
			(options
				(clearance outline)
				(anchor circle)
			)
			(primitives
				(gr_poly
					(pts
						(arc
							(start -0.1778 -0.2794)
							(mid -0.249642 -0.249642)
							(end -0.2794 -0.1778)
						)
						(arc
							(start -0.2794 0.1778)
							(mid -0.249642 0.249642)
							(end -0.1778 0.2794)
						)
						(arc
							(start 0.1778 0.2794)
							(mid 0.249642 0.249642)
							(end 0.2794 0.1778)
						)
						(arc
							(start 0.2794 -0.1778)
							(mid 0.249642 -0.249642)
							(end 0.1778 -0.2794)
						)
					)
					(width 0)
					(fill yes)
				)
			)
		)
		(pad "2" smd custom
			(at 0 0.4445)
			(size 0.1397 0.1397)
			(layers "F.Cu" "F.Mask" "F.Paste")
			(net "GND")
			(options
				(clearance outline)
				(anchor circle)
			)
			(primitives
				(gr_poly
					(pts
						(arc
							(start -0.1778 -0.2794)
							(mid -0.249642 -0.249642)
							(end -0.2794 -0.1778)
						)
						(arc
							(start -0.2794 0.1778)
							(mid -0.249642 0.249642)
							(end -0.1778 0.2794)
						)
						(arc
							(start 0.1778 0.2794)
							(mid 0.249642 0.249642)
							(end 0.2794 0.1778)
						)
						(arc
							(start 0.2794 -0.1778)
							(mid 0.249642 -0.249642)
							(end 0.1778 -0.2794)
						)
					)
					(width 0)
					(fill yes)
				)
			)
		)
	)
	(footprint ""
		(layer "F.Cu")
		(at 246.253 -387.4008 -90)
		(property "Reference" "R1157"
			(at 0 0 270)
			(layer "F.SilkS")
			(hide yes)
			(effects
				(font
					(size 1.27 1.27)
				)
			)
		)
		(property "Value" "10R2F-L-GP"
			(at 0.064008 -3.993896 270)
			(unlocked yes)
			(layer "F.Fab")
			(hide yes)
			(effects
				(font
					(size 1.016 1.016)
					(thickness 0.1524)
				)
			)
		)
		(property "Device Type" "R402H14"
			(at 0.064008 -5.517896 270)
			(unlocked yes)
			(layer "F.Fab")
			(hide yes)
			(effects
				(font
					(size 1.016 1.016)
					(thickness 0.1524)
				)
			)
		)
		(duplicate_pad_numbers_are_jumpers no)
		(fp_line
			(start -0.508 -0.9398)
			(end -0.508 0.9398)
			(stroke
				(width 0.1524)
				(type default)
			)
			(layer "F.SilkS")
		)
		(fp_line
			(start 0.508 -0.9398)
			(end -0.508 -0.9398)
			(stroke
				(width 0.1524)
				(type default)
			)
			(layer "F.SilkS")
		)
		(fp_rect
			(start -0.508 0.9398)
			(end 0.508 -0.9398)
			(stroke
				(width 0)
				(type default)
			)
			(fill no)
			(layer "F.CrtYd")
		)
		(fp_rect
			(start -0.508 0.9398)
			(end 0.508 -0.9398)
			(stroke
				(width 0)
				(type default)
			)
			(fill no)
			(layer "F.Fab")
		)
		(pad "1" smd custom
			(at 0 -0.4445 270)
			(size 0.1397 0.1397)
			(layers "F.Cu" "F.Mask" "F.Paste")
			(net "MB3_CM_SENSE_R1_N")
			(options
				(clearance outline)
				(anchor circle)
			)
			(primitives
				(gr_poly
					(pts
						(arc
							(start -0.1778 -0.2794)
							(mid -0.249642 -0.249642)
							(end -0.2794 -0.1778)
						)
						(arc
							(start -0.2794 0.1778)
							(mid -0.249642 0.249642)
							(end -0.1778 0.2794)
						)
						(arc
							(start 0.1778 0.2794)
							(mid 0.249642 0.249642)
							(end 0.2794 0.1778)
						)
						(arc
							(start 0.2794 -0.1778)
							(mid 0.249642 -0.249642)
							(end 0.1778 -0.2794)
						)
					)
					(width 0)
					(fill yes)
				)
			)
		)
		(pad "2" smd custom
			(at 0 0.4445 270)
			(size 0.1397 0.1397)
			(layers "F.Cu" "F.Mask" "F.Paste")
			(net "MB3_HS_SENSE_N")
			(options
				(clearance outline)
				(anchor circle)
			)
			(primitives
				(gr_poly
					(pts
						(arc
							(start -0.1778 -0.2794)
							(mid -0.249642 -0.249642)
							(end -0.2794 -0.1778)
						)
						(arc
							(start -0.2794 0.1778)
							(mid -0.249642 0.249642)
							(end -0.1778 0.2794)
						)
						(arc
							(start 0.1778 0.2794)
							(mid 0.249642 0.249642)
							(end 0.2794 0.1778)
						)
						(arc
							(start 0.2794 -0.1778)
							(mid 0.249642 -0.249642)
							(end 0.1778 -0.2794)
						)
					)
					(width 0)
					(fill yes)
				)
			)
		)
	)
	(footprint ""
		(layer "F.Cu")
		(at 403.095968 -127.788924 180)
		(property "Reference" "Q284"
			(at 0 0 180)
			(layer "F.SilkS")
			(hide yes)
			(effects
				(font
					(size 1.27 1.27)
				)
			)
		)
		(property "Value" "SSM3K324R-GP"
			(at 0.127 -8.9662 180)
			(unlocked yes)
			(layer "F.Fab")
			(hide yes)
			(effects
				(font
					(size 1.016 1.016)
					(thickness 0.1524)
				)
			)
		)
		(property "Device Type" "SOT23DGS2D4H35"
			(at 0.127 -10.4902 180)
			(unlocked yes)
			(layer "F.Fab")
			(hide yes)
			(effects
				(font
					(size 1.016 1.016)
					(thickness 0.1524)
				)
			)
		)
		(duplicate_pad_numbers_are_jumpers no)
		(fp_line
			(start 1.651 1.778)
			(end 1.651 -1.778)
			(stroke
				(width 0.1524)
				(type default)
			)
			(layer "F.SilkS")
		)
		(fp_line
			(start 1.651 -1.778)
			(end -1.651 -1.778)
			(stroke
				(width 0.1524)
				(type default)
			)
			(layer "F.SilkS")
		)
		(fp_line
			(start -1.651 1.778)
			(end 1.651 1.778)
			(stroke
				(width 0.1524)
				(type default)
			)
			(layer "F.SilkS")
		)
		(fp_line
			(start -1.651 -1.778)
			(end -1.651 1.778)
			(stroke
				(width 0.1524)
				(type default)
			)
			(layer "F.SilkS")
		)
		(fp_poly
			(pts
				(xy -1.778 1.8796) (xy -1.778 -1.8796) (xy 1.778 -1.8796) (xy 1.778 1.8796)
			)
			(stroke
				(width 0)
				(type default)
			)
			(fill no)
			(layer "F.CrtYd")
		)
		(fp_poly
			(pts
				(xy -1.778 1.8796) (xy -1.778 -1.8796) (xy 1.778 -1.8796) (xy 1.778 1.8796)
			)
			(stroke
				(width 0)
				(type default)
			)
			(fill no)
			(layer "F.Fab")
		)
		(pad "D" smd custom
			(at 0 -0.9525 180)
			(size 0.1905 0.1905)
			(layers "F.Cu" "F.Mask" "F.Paste")
			(net "DRV_ACT_21_N")
			(options
				(clearance outline)
				(anchor circle)
			)
			(primitives
				(gr_poly
					(pts
						(arc
							(start -0.1778 0.5715)
							(mid -0.321484 0.511984)
							(end -0.381 0.3683)
						)
						(arc
							(start -0.381 -0.3683)
							(mid -0.321484 -0.511984)
							(end -0.1778 -0.5715)
						)
						(arc
							(start 0.1778 -0.5715)
							(mid 0.321484 -0.511984)
							(end 0.381 -0.3683)
						)
						(arc
							(start 0.381 0.3683)
							(mid 0.321484 0.511984)
							(end 0.1778 0.5715)
						)
					)
					(width 0)
					(fill yes)
				)
			)
		)
		(pad "G" smd custom
			(at -0.98425 0.9525 180)
			(size 0.1905 0.1905)
			(layers "F.Cu" "F.Mask" "F.Paste")
			(net "DRIVE_A_21_ACT")
			(options
				(clearance outline)
				(anchor circle)
			)
			(primitives
				(gr_poly
					(pts
						(arc
							(start -0.1778 0.5715)
							(mid -0.321484 0.511984)
							(end -0.381 0.3683)
						)
						(arc
							(start -0.381 -0.3683)
							(mid -0.321484 -0.511984)
							(end -0.1778 -0.5715)
						)
						(arc
							(start 0.1778 -0.5715)
							(mid 0.321484 -0.511984)
							(end 0.381 -0.3683)
						)
						(arc
							(start 0.381 0.3683)
							(mid 0.321484 0.511984)
							(end 0.1778 0.5715)
						)
					)
					(width 0)
					(fill yes)
				)
			)
		)
		(pad "S" smd custom
			(at 0.98425 0.9525 180)
			(size 0.1905 0.1905)
			(layers "F.Cu" "F.Mask" "F.Paste")
			(net "GND")
			(options
				(clearance outline)
				(anchor circle)
			)
			(primitives
				(gr_poly
					(pts
						(arc
							(start -0.1778 0.5715)
							(mid -0.321484 0.511984)
							(end -0.381 0.3683)
						)
						(arc
							(start -0.381 -0.3683)
							(mid -0.321484 -0.511984)
							(end -0.1778 -0.5715)
						)
						(arc
							(start 0.1778 -0.5715)
							(mid 0.321484 -0.511984)
							(end 0.381 -0.3683)
						)
						(arc
							(start 0.381 0.3683)
							(mid 0.321484 0.511984)
							(end 0.1778 0.5715)
						)
					)
					(width 0)
					(fill yes)
				)
			)
		)
	)
	(footprint ""
		(layer "F.Cu")
		(at 147.248372 -145.388838 180)
		(property "Reference" "R1059"
			(at 0 0 180)
			(layer "F.SilkS")
			(hide yes)
			(effects
				(font
					(size 1.27 1.27)
				)
			)
		)
		(property "Value" "62KR2F-GP"
			(at 0.064008 -3.993896 180)
			(unlocked yes)
			(layer "F.Fab")
			(hide yes)
			(effects
				(font
					(size 1.016 1.016)
					(thickness 0.1524)
				)
			)
		)
		(property "Device Type" "R402H16"
			(at 0.064008 -5.517896 180)
			(unlocked yes)
			(layer "F.Fab")
			(hide yes)
			(effects
				(font
					(size 1.016 1.016)
					(thickness 0.1524)
				)
			)
		)
		(duplicate_pad_numbers_are_jumpers no)
		(fp_line
			(start 0.508 -0.9398)
			(end -0.508 -0.9398)
			(stroke
				(width 0.1524)
				(type default)
			)
			(layer "F.SilkS")
		)
		(fp_line
			(start -0.508 -0.9398)
			(end -0.508 0.9398)
			(stroke
				(width 0.1524)
				(type default)
			)
			(layer "F.SilkS")
		)
		(fp_rect
			(start -0.508 0.9398)
			(end 0.508 -0.9398)
			(stroke
				(width 0)
				(type default)
			)
			(fill no)
			(layer "F.CrtYd")
		)
		(fp_rect
			(start -0.508 0.9398)
			(end 0.508 -0.9398)
			(stroke
				(width 0)
				(type default)
			)
			(fill no)
			(layer "F.Fab")
		)
		(pad "1" smd custom
			(at 0 -0.4445 180)
			(size 0.1397 0.1397)
			(layers "F.Cu" "F.Mask" "F.Paste")
			(net "MB0_ISET_R")
			(options
				(clearance outline)
				(anchor circle)
			)
			(primitives
				(gr_poly
					(pts
						(arc
							(start -0.1778 -0.2794)
							(mid -0.249642 -0.249642)
							(end -0.2794 -0.1778)
						)
						(arc
							(start -0.2794 0.1778)
							(mid -0.249642 0.249642)
							(end -0.1778 0.2794)
						)
						(arc
							(start 0.1778 0.2794)
							(mid 0.249642 0.249642)
							(end 0.2794 0.1778)
						)
						(arc
							(start 0.2794 -0.1778)
							(mid 0.249642 -0.249642)
							(end 0.1778 -0.2794)
						)
					)
					(width 0)
					(fill yes)
				)
			)
		)
		(pad "2" smd custom
			(at 0 0.4445 180)
			(size 0.1397 0.1397)
			(layers "F.Cu" "F.Mask" "F.Paste")
			(net "AGND_CURRENT_MONOA")
			(options
				(clearance outline)
				(anchor circle)
			)
			(primitives
				(gr_poly
					(pts
						(arc
							(start -0.1778 -0.2794)
							(mid -0.249642 -0.249642)
							(end -0.2794 -0.1778)
						)
						(arc
							(start -0.2794 0.1778)
							(mid -0.249642 0.249642)
							(end -0.1778 0.2794)
						)
						(arc
							(start 0.1778 0.2794)
							(mid 0.249642 0.249642)
							(end 0.2794 0.1778)
						)
						(arc
							(start 0.2794 -0.1778)
							(mid 0.249642 -0.249642)
							(end 0.1778 -0.2794)
						)
					)
					(width 0)
					(fill yes)
				)
			)
		)
	)
	(footprint ""
		(layer "F.Cu")
		(at 364.5408 -132.1054)
		(property "Reference" "R1091"
			(at 0 0 0)
			(layer "F.SilkS")
			(hide yes)
			(effects
				(font
					(size 1.27 1.27)
				)
			)
		)
		(property "Value" "137KR2F-1-GP"
			(at 0.064008 -3.993896 0)
			(unlocked yes)
			(layer "F.Fab")
			(hide yes)
			(effects
				(font
					(size 1.016 1.016)
					(thickness 0.1524)
				)
			)
		)
		(property "Device Type" "R402H16"
			(at 0.064008 -5.517896 0)
			(unlocked yes)
			(layer "F.Fab")
			(hide yes)
			(effects
				(font
					(size 1.016 1.016)
					(thickness 0.1524)
				)
			)
		)
		(duplicate_pad_numbers_are_jumpers no)
		(fp_line
			(start -0.508 -0.9398)
			(end -0.508 0.9398)
			(stroke
				(width 0.1524)
				(type default)
			)
			(layer "F.SilkS")
		)
		(fp_line
			(start 0.508 -0.9398)
			(end -0.508 -0.9398)
			(stroke
				(width 0.1524)
				(type default)
			)
			(layer "F.SilkS")
		)
		(fp_rect
			(start -0.508 0.9398)
			(end 0.508 -0.9398)
			(stroke
				(width 0)
				(type default)
			)
			(fill no)
			(layer "F.CrtYd")
		)
		(fp_rect
			(start -0.508 0.9398)
			(end 0.508 -0.9398)
			(stroke
				(width 0)
				(type default)
			)
			(fill no)
			(layer "F.Fab")
		)
		(pad "1" smd custom
			(at 0 -0.4445)
			(size 0.1397 0.1397)
			(layers "F.Cu" "F.Mask" "F.Paste")
			(net "MB1_PSET_R")
			(options
				(clearance outline)
				(anchor circle)
			)
			(primitives
				(gr_poly
					(pts
						(arc
							(start -0.1778 -0.2794)
							(mid -0.249642 -0.249642)
							(end -0.2794 -0.1778)
						)
						(arc
							(start -0.2794 0.1778)
							(mid -0.249642 0.249642)
							(end -0.1778 0.2794)
						)
						(arc
							(start 0.1778 0.2794)
							(mid 0.249642 0.249642)
							(end 0.2794 0.1778)
						)
						(arc
							(start 0.2794 -0.1778)
							(mid 0.249642 -0.249642)
							(end 0.1778 -0.2794)
						)
					)
					(width 0)
					(fill yes)
				)
			)
		)
		(pad "2" smd custom
			(at 0 0.4445)
			(size 0.1397 0.1397)
			(layers "F.Cu" "F.Mask" "F.Paste")
			(net "AGND_CURRENT_MONOB")
			(options
				(clearance outline)
				(anchor circle)
			)
			(primitives
				(gr_poly
					(pts
						(arc
							(start -0.1778 -0.2794)
							(mid -0.249642 -0.249642)
							(end -0.2794 -0.1778)
						)
						(arc
							(start -0.2794 0.1778)
							(mid -0.249642 0.249642)
							(end -0.1778 0.2794)
						)
						(arc
							(start 0.1778 0.2794)
							(mid 0.249642 0.249642)
							(end 0.2794 0.1778)
						)
						(arc
							(start 0.2794 -0.1778)
							(mid 0.249642 -0.249642)
							(end 0.1778 -0.2794)
						)
					)
					(width 0)
					(fill yes)
				)
			)
		)
	)
	(footprint ""
		(layer "F.Cu")
		(at 387.83895 -277.750016 -90)
		(property "Reference" "VIA19"
			(at 0 0 270)
			(layer "F.SilkS")
			(hide yes)
			(effects
				(font
					(size 1.27 1.27)
				)
			)
		)
		(property "Value" "100OHM-8L-1D6MM-L18L16-GP"
			(at -3.7211 -4.5085 270)
			(unlocked yes)
			(layer "F.Fab")
			(hide yes)
			(effects
				(font
					(size 1.016 1.016)
					(thickness 0.1524)
				)
			)
		)
		(property "Device Type" "VIA-PCIE-4P-394076"
			(at -3.7211 -6.0325 270)
			(unlocked yes)
			(layer "F.Fab")
			(hide yes)
			(effects
				(font
					(size 1.016 1.016)
					(thickness 0.1524)
				)
			)
		)
		(duplicate_pad_numbers_are_jumpers no)
		(fp_rect
			(start -1.9685 0.381)
			(end 1.9685 -0.381)
			(stroke
				(width 0)
				(type default)
			)
			(fill no)
			(layer "F.CrtYd")
		)
		(fp_rect
			(start -1.9685 0.381)
			(end 1.9685 -0.381)
			(stroke
				(width 0)
				(type default)
			)
			(fill no)
			(layer "F.Fab")
		)
		(pad "1" thru_hole circle
			(at -1.5875 0 270)
			(size 0.508 0.508)
			(drill 0.254)
			(layers "*.Cu" "*.Mask")
			(remove_unused_layers no)
			(net "GND")
			(clearance 0.127)
			(thermal_gap 0.127)
		)
		(pad "2" thru_hole circle
			(at -0.5715 0 270)
			(size 0.508 0.508)
			(drill 0.254)
			(layers "*.Cu" "*.Mask")
			(remove_unused_layers no)
			(net "PHY_DRV_A_TO_SCC_A_8_DP")
			(clearance 0.127)
			(thermal_gap 0.127)
		)
		(pad "3" thru_hole circle
			(at 0.5715 0 270)
			(size 0.508 0.508)
			(drill 0.254)
			(layers "*.Cu" "*.Mask")
			(remove_unused_layers no)
			(net "PHY_DRV_A_TO_SCC_A_8_DN")
			(clearance 0.127)
			(thermal_gap 0.127)
		)
		(pad "4" thru_hole circle
			(at 1.5875 0 270)
			(size 0.508 0.508)
			(drill 0.254)
			(layers "*.Cu" "*.Mask")
			(remove_unused_layers no)
			(net "GND")
			(clearance 0.127)
			(thermal_gap 0.127)
		)
	)
	(footprint ""
		(layer "F.Cu")
		(at 338.565236 -33.550352 180)
		(property "Reference" "R70"
			(at 0 0 180)
			(layer "F.SilkS")
			(hide yes)
			(effects
				(font
					(size 1.27 1.27)
				)
			)
		)
		(property "Value" "4K7R2F-GP"
			(at 0.064008 -3.993896 180)
			(unlocked yes)
			(layer "F.Fab")
			(hide yes)
			(effects
				(font
					(size 1.016 1.016)
					(thickness 0.1524)
				)
			)
		)
		(property "Device Type" "R402H16"
			(at 0.064008 -5.517896 180)
			(unlocked yes)
			(layer "F.Fab")
			(hide yes)
			(effects
				(font
					(size 1.016 1.016)
					(thickness 0.1524)
				)
			)
		)
		(duplicate_pad_numbers_are_jumpers no)
		(fp_line
			(start 0.508 -0.9398)
			(end -0.508 -0.9398)
			(stroke
				(width 0.1524)
				(type default)
			)
			(layer "F.SilkS")
		)
		(fp_line
			(start -0.508 -0.9398)
			(end -0.508 0.9398)
			(stroke
				(width 0.1524)
				(type default)
			)
			(layer "F.SilkS")
		)
		(fp_rect
			(start -0.508 0.9398)
			(end 0.508 -0.9398)
			(stroke
				(width 0)
				(type default)
			)
			(fill no)
			(layer "F.CrtYd")
		)
		(fp_rect
			(start -0.508 0.9398)
			(end 0.508 -0.9398)
			(stroke
				(width 0)
				(type default)
			)
			(fill no)
			(layer "F.Fab")
		)
		(pad "1" smd custom
			(at 0 -0.4445 180)
			(size 0.1397 0.1397)
			(layers "F.Cu" "F.Mask" "F.Paste")
			(net "IO_EXP11_A0")
			(options
				(clearance outline)
				(anchor circle)
			)
			(primitives
				(gr_poly
					(pts
						(arc
							(start -0.1778 -0.2794)
							(mid -0.249642 -0.249642)
							(end -0.2794 -0.1778)
						)
						(arc
							(start -0.2794 0.1778)
							(mid -0.249642 0.249642)
							(end -0.1778 0.2794)
						)
						(arc
							(start 0.1778 0.2794)
							(mid 0.249642 0.249642)
							(end 0.2794 0.1778)
						)
						(arc
							(start 0.2794 -0.1778)
							(mid 0.249642 -0.249642)
							(end 0.1778 -0.2794)
						)
					)
					(width 0)
					(fill yes)
				)
			)
		)
		(pad "2" smd custom
			(at 0 0.4445 180)
			(size 0.1397 0.1397)
			(layers "F.Cu" "F.Mask" "F.Paste")
			(net "GND")
			(options
				(clearance outline)
				(anchor circle)
			)
			(primitives
				(gr_poly
					(pts
						(arc
							(start -0.1778 -0.2794)
							(mid -0.249642 -0.249642)
							(end -0.2794 -0.1778)
						)
						(arc
							(start -0.2794 0.1778)
							(mid -0.249642 0.249642)
							(end -0.1778 0.2794)
						)
						(arc
							(start 0.1778 0.2794)
							(mid 0.249642 0.249642)
							(end 0.2794 0.1778)
						)
						(arc
							(start 0.2794 -0.1778)
							(mid 0.249642 -0.249642)
							(end 0.1778 -0.2794)
						)
					)
					(width 0)
					(fill yes)
				)
			)
		)
	)
)
